FILE_TYPE = MULTI_PHYS_TABLE;

PART 'TP'
CLASS=IO

{========================================================================================}
:PACK_TYPE | MATERIAL | PART_NUMBER    = STANDARD         | LIFECYCLE        | PART_NUMBER | JEDEC_TYPE | HEIGHT |  COMPONENT_TYPE | LEAD_LENGTH ;
{========================================================================================}
 'TP'      | 'na'     | 'TP26D10'(!)   = ''               | ''               | 'TP26D10'   |'TP26D10'| ''     |  'PSEUDO'       | ''         
 'TP'      | 'EMPTY'  | 'TP26D10'(!)   = ''               | ''               | 'TP26D10'   |'TP26D10'| ''     |  'PSEUDO'       | ''         
 'TP'      | 'na'     | 'TP30'(!)      = ''               | ''               | 'TP30'      |'TP30'| ''     |  'PSEUDO'       | ''         
 'TP'      | 'EMPTY'  | 'TP30'(!)      = ''               | ''               | 'TP30'      |'TP30'| ''     |  'PSEUDO'       | ''         
 'TP'      | 'na'     | 'TP26'(!)      = ''               | ''               | 'TP26'      |'TP26'| ''     |  'PSEUDO'       | ''         
 'TP'      | 'EMPTY'  | 'TP26'(!)      = ''               | ''               | 'TP26'      |'TP26'| ''     |  'PSEUDO'       | ''         
 'TP_BOM ONLY'      | 'na'     | 'TP12_BOM'(!)      = ''               | ''               | 'TP12_BOM'      |'TP30'| ''     |  'PSEUDO'       | ''         
 'TP_BOM ONLY'      | 'EMPTY'  | 'TP12_BOM'(!)      = ''               | ''               | 'TP12_BOM'      |'TP30'| ''     |  'PSEUDO'       | ''         

END_PART

END.

